(kicad_pcb
	(version 20260206)
	(generator "pcbnew")
	(generator_version "10.0")
	(general
		(thickness 1.6)
		(legacy_teardrops no)
	)
	(paper "A4")
	(title_block
		(title "01162023_DA0F0TEBIF0_F0T_Expander_BD_F_brd_V02_OCP.brd")
		(comment 1 "Grand Teton / footprints 485-491 of 9728")
	)
	(layers
		(0 "F.Cu" signal "TOP")
		(4 "In1.Cu" signal "GND")
		(6 "In2.Cu" signal "VCC")
		(8 "In3.Cu" signal "VCC1")
		(10 "In4.Cu" signal "GND1")
		(12 "In5.Cu" signal "IN1")
		(14 "In6.Cu" signal "GND2")
		(16 "In7.Cu" signal "IN2")
		(18 "In8.Cu" signal "GND3")
		(20 "In9.Cu" signal "IN3")
		(22 "In10.Cu" signal "GND4")
		(24 "In11.Cu" signal "IN4")
		(26 "In12.Cu" signal "GND5")
		(28 "In13.Cu" signal "IN5")
		(30 "In14.Cu" signal "GND6")
		(32 "In15.Cu" signal "IN6")
		(34 "In16.Cu" signal "GND7")
		(2 "B.Cu" signal "BOTTOM")
		(9 "F.Adhes" user "F.Adhesive")
		(11 "B.Adhes" user "B.Adhesive")
		(13 "F.Paste" user "Package Geometry/Pastemask Top")
		(15 "B.Paste" user "Package Geometry/Pastemask Bottom")
		(5 "F.SilkS" user "Ref Des/Silkscreen Top")
		(7 "B.SilkS" user "Ref Des/Silkscreen Bottom")
		(1 "F.Mask" user "Board Geometry/Soldermask Top")
		(3 "B.Mask" user "Board Geometry/Soldermask Bottom")
		(17 "Dwgs.User" user "User.Drawings")
		(19 "Cmts.User" user "User.Comments")
		(21 "Eco1.User" user "User.Eco1")
		(23 "Eco2.User" user "User.Eco2")
		(25 "Edge.Cuts" user "Board Geometry/Outline")
		(27 "Margin" user)
		(31 "F.CrtYd" user "Package Geometry/Place Bound Top")
		(29 "B.CrtYd" user "Package Geometry/Place Bound Bottom")
		(35 "F.Fab" user "Ref Des/Assembly Top")
		(33 "B.Fab" user "Ref Des/Assembly Bottom")
	)
	(footprint ""
		(layer "F.Cu")
		(at 434.071776 -24.807418)
		(property "Reference" "R456"
			(at 0 0 0)
			(layer "F.SilkS")
			(hide yes)
			(effects
				(font
					(size 1.27 1.27)
				)
			)
		)
		(property "Value" ""
			(at 0 0 0)
			(layer "F.Fab")
			(effects
				(font
					(size 1.27 1.27)
				)
			)
		)
		(duplicate_pad_numbers_are_jumpers no)
		(fp_line
			(start -0.7874 -0.4064)
			(end 0.7874 -0.4064)
			(stroke
				(width 0.1524)
				(type default)
			)
			(layer "F.SilkS")
		)
		(fp_line
			(start -0.7874 0.4064)
			(end -0.7874 -0.4064)
			(stroke
				(width 0.1524)
				(type default)
			)
			(layer "F.SilkS")
		)
		(fp_line
			(start 0.7874 -0.4064)
			(end 0.7874 0.4064)
			(stroke
				(width 0.1524)
				(type default)
			)
			(layer "F.SilkS")
		)
		(fp_line
			(start 0.7874 0.4064)
			(end -0.7874 0.4064)
			(stroke
				(width 0.1524)
				(type default)
			)
			(layer "F.SilkS")
		)
		(fp_line
			(start -0.67945 -0.305054)
			(end -0.12065 -0.305054)
			(stroke
				(width 0.1)
				(type default)
			)
			(layer "F.Fab")
		)
		(fp_line
			(start -0.67945 0.3048)
			(end -0.67945 -0.305054)
			(stroke
				(width 0.1)
				(type default)
			)
			(layer "F.Fab")
		)
		(fp_line
			(start -0.12065 -0.305054)
			(end -0.12065 -0.2794)
			(stroke
				(width 0.1)
				(type default)
			)
			(layer "F.Fab")
		)
		(fp_line
			(start -0.12065 -0.2794)
			(end 0.12065 -0.2794)
			(stroke
				(width 0.1)
				(type default)
			)
			(layer "F.Fab")
		)
		(fp_line
			(start -0.12065 0.2794)
			(end -0.12065 0.3048)
			(stroke
				(width 0.1)
				(type default)
			)
			(layer "F.Fab")
		)
		(fp_line
			(start -0.12065 0.3048)
			(end -0.67945 0.3048)
			(stroke
				(width 0.1)
				(type default)
			)
			(layer "F.Fab")
		)
		(fp_line
			(start 0.120396 0.2794)
			(end -0.12065 0.2794)
			(stroke
				(width 0.1)
				(type default)
			)
			(layer "F.Fab")
		)
		(fp_line
			(start 0.120396 0.3048)
			(end 0.120396 0.2794)
			(stroke
				(width 0.1)
				(type default)
			)
			(layer "F.Fab")
		)
		(fp_line
			(start 0.12065 -0.3048)
			(end 0.67945 -0.3048)
			(stroke
				(width 0.1)
				(type default)
			)
			(layer "F.Fab")
		)
		(fp_line
			(start 0.12065 -0.2794)
			(end 0.12065 -0.3048)
			(stroke
				(width 0.1)
				(type default)
			)
			(layer "F.Fab")
		)
		(fp_line
			(start 0.67945 -0.3048)
			(end 0.67945 0.3048)
			(stroke
				(width 0.1)
				(type default)
			)
			(layer "F.Fab")
		)
		(fp_line
			(start 0.67945 0.3048)
			(end 0.120396 0.3048)
			(stroke
				(width 0.1)
				(type default)
			)
			(layer "F.Fab")
		)
		(pad "1" smd circle
			(at -0.40005 0)
			(size 0 0)
			(layers "F.Cu" "F.Mask" "F.Paste")
			(net "P3V3_SSD15")
		)
		(pad "2" smd circle
			(at 0.40005 0)
			(size 0 0)
			(layers "F.Cu" "F.Mask" "F.Paste")
			(net "PU_CLKREQ15")
		)
	)
	(footprint ""
		(layer "F.Cu")
		(at 239.935512 -234.728004 -90)
		(property "Reference" "R6183"
			(at 0 0 270)
			(layer "F.SilkS")
			(hide yes)
			(effects
				(font
					(size 1.27 1.27)
				)
			)
		)
		(property "Value" ""
			(at 0 0 270)
			(layer "F.Fab")
			(effects
				(font
					(size 1.27 1.27)
				)
			)
		)
		(duplicate_pad_numbers_are_jumpers no)
		(fp_line
			(start -0.7874 0.4064)
			(end -0.7874 -0.4064)
			(stroke
				(width 0.1524)
				(type default)
			)
			(layer "F.SilkS")
		)
		(fp_line
			(start 0.7874 0.4064)
			(end -0.7874 0.4064)
			(stroke
				(width 0.1524)
				(type default)
			)
			(layer "F.SilkS")
		)
		(fp_line
			(start -0.7874 -0.4064)
			(end 0.7874 -0.4064)
			(stroke
				(width 0.1524)
				(type default)
			)
			(layer "F.SilkS")
		)
		(fp_line
			(start 0.7874 -0.4064)
			(end 0.7874 0.4064)
			(stroke
				(width 0.1524)
				(type default)
			)
			(layer "F.SilkS")
		)
		(fp_line
			(start -0.67945 0.3048)
			(end -0.67945 -0.305054)
			(stroke
				(width 0.1)
				(type default)
			)
			(layer "F.Fab")
		)
		(fp_line
			(start -0.12065 0.3048)
			(end -0.67945 0.3048)
			(stroke
				(width 0.1)
				(type default)
			)
			(layer "F.Fab")
		)
		(fp_line
			(start 0.120396 0.3048)
			(end 0.120396 0.2794)
			(stroke
				(width 0.1)
				(type default)
			)
			(layer "F.Fab")
		)
		(fp_line
			(start 0.67945 0.3048)
			(end 0.120396 0.3048)
			(stroke
				(width 0.1)
				(type default)
			)
			(layer "F.Fab")
		)
		(fp_line
			(start -0.12065 0.2794)
			(end -0.12065 0.3048)
			(stroke
				(width 0.1)
				(type default)
			)
			(layer "F.Fab")
		)
		(fp_line
			(start 0.120396 0.2794)
			(end -0.12065 0.2794)
			(stroke
				(width 0.1)
				(type default)
			)
			(layer "F.Fab")
		)
		(fp_line
			(start -0.12065 -0.2794)
			(end 0.12065 -0.2794)
			(stroke
				(width 0.1)
				(type default)
			)
			(layer "F.Fab")
		)
		(fp_line
			(start 0.12065 -0.2794)
			(end 0.12065 -0.3048)
			(stroke
				(width 0.1)
				(type default)
			)
			(layer "F.Fab")
		)
		(fp_line
			(start 0.12065 -0.3048)
			(end 0.67945 -0.3048)
			(stroke
				(width 0.1)
				(type default)
			)
			(layer "F.Fab")
		)
		(fp_line
			(start 0.67945 -0.3048)
			(end 0.67945 0.3048)
			(stroke
				(width 0.1)
				(type default)
			)
			(layer "F.Fab")
		)
		(fp_line
			(start -0.67945 -0.305054)
			(end -0.12065 -0.305054)
			(stroke
				(width 0.1)
				(type default)
			)
			(layer "F.Fab")
		)
		(fp_line
			(start -0.12065 -0.305054)
			(end -0.12065 -0.2794)
			(stroke
				(width 0.1)
				(type default)
			)
			(layer "F.Fab")
		)
		(pad "1" smd circle
			(at -0.40005 0 270)
			(size 0 0)
			(layers "F.Cu" "F.Mask" "F.Paste")
			(net "GND")
		)
		(pad "2" smd circle
			(at 0.40005 0 270)
			(size 0 0)
			(layers "F.Cu" "F.Mask" "F.Paste")
			(net "SSD1_PWRDIS_BIC_R")
		)
	)
	(footprint ""
		(layer "F.Cu")
		(at 324.552564 -311.197244 135)
		(property "Reference" "R1382"
			(at 0 0 135)
			(layer "F.SilkS")
			(hide yes)
			(effects
				(font
					(size 1.27 1.27)
				)
			)
		)
		(property "Value" ""
			(at 0 0 135)
			(layer "F.Fab")
			(effects
				(font
					(size 1.27 1.27)
				)
			)
		)
		(duplicate_pad_numbers_are_jumpers no)
		(fp_line
			(start 0.787389 -0.406267)
			(end 0.787389 0.406267)
			(stroke
				(width 0.1524)
				(type default)
			)
			(layer "F.SilkS")
		)
		(fp_line
			(start 0.787389 0.406267)
			(end -0.787389 0.406267)
			(stroke
				(width 0.1524)
				(type default)
			)
			(layer "F.SilkS")
		)
		(fp_line
			(start -0.787389 -0.406267)
			(end 0.787389 -0.406267)
			(stroke
				(width 0.1524)
				(type default)
			)
			(layer "F.SilkS")
		)
		(fp_line
			(start -0.787389 0.406267)
			(end -0.787389 -0.406267)
			(stroke
				(width 0.1524)
				(type default)
			)
			(layer "F.SilkS")
		)
		(fp_line
			(start 0.679446 -0.30479)
			(end 0.679446 0.30479)
			(stroke
				(width 0.1)
				(type default)
			)
			(layer "F.Fab")
		)
		(fp_line
			(start 0.120515 -0.30479)
			(end 0.679446 -0.30479)
			(stroke
				(width 0.1)
				(type default)
			)
			(layer "F.Fab")
		)
		(fp_line
			(start 0.120695 -0.279466)
			(end 0.120515 -0.30479)
			(stroke
				(width 0.1)
				(type default)
			)
			(layer "F.Fab")
		)
		(fp_line
			(start 0.679446 0.30479)
			(end 0.120515 0.30479)
			(stroke
				(width 0.1)
				(type default)
			)
			(layer "F.Fab")
		)
		(fp_line
			(start -0.120695 -0.304969)
			(end -0.120695 -0.279466)
			(stroke
				(width 0.1)
				(type default)
			)
			(layer "F.Fab")
		)
		(fp_line
			(start -0.120695 -0.279466)
			(end 0.120695 -0.279466)
			(stroke
				(width 0.1)
				(type default)
			)
			(layer "F.Fab")
		)
		(fp_line
			(start 0.120335 0.279466)
			(end -0.120695 0.279466)
			(stroke
				(width 0.1)
				(type default)
			)
			(layer "F.Fab")
		)
		(fp_line
			(start 0.120515 0.30479)
			(end 0.120335 0.279466)
			(stroke
				(width 0.1)
				(type default)
			)
			(layer "F.Fab")
		)
		(fp_line
			(start -0.679446 -0.305149)
			(end -0.120695 -0.304969)
			(stroke
				(width 0.1)
				(type default)
			)
			(layer "F.Fab")
		)
		(fp_line
			(start -0.120695 0.279466)
			(end -0.120515 0.30479)
			(stroke
				(width 0.1)
				(type default)
			)
			(layer "F.Fab")
		)
		(fp_line
			(start -0.120515 0.30479)
			(end -0.679446 0.30479)
			(stroke
				(width 0.1)
				(type default)
			)
			(layer "F.Fab")
		)
		(fp_line
			(start -0.679446 0.30479)
			(end -0.679446 -0.305149)
			(stroke
				(width 0.1)
				(type default)
			)
			(layer "F.Fab")
		)
		(pad "1" smd circle
			(at -0.40005 0 135)
			(size 0 0)
			(layers "F.Cu" "F.Mask" "F.Paste")
			(net "GND")
		)
		(pad "2" smd circle
			(at 0.40005 0 135)
			(size 0 0)
			(layers "F.Cu" "F.Mask" "F.Paste")
			(net "PEX2_SPARE5")
		)
	)
	(footprint ""
		(layer "F.Cu")
		(at 320.167 -83.058)
		(property "Reference" "C3992"
			(at 0 0 0)
			(layer "F.SilkS")
			(hide yes)
			(effects
				(font
					(size 1.27 1.27)
				)
			)
		)
		(property "Value" ""
			(at 0 0 0)
			(layer "F.Fab")
			(effects
				(font
					(size 1.27 1.27)
				)
			)
		)
		(duplicate_pad_numbers_are_jumpers no)
		(fp_line
			(start -0.7874 -0.4064)
			(end 0.7874 -0.4064)
			(stroke
				(width 0.1524)
				(type default)
			)
			(layer "F.SilkS")
		)
		(fp_line
			(start -0.7874 0.4064)
			(end -0.7874 -0.4064)
			(stroke
				(width 0.1524)
				(type default)
			)
			(layer "F.SilkS")
		)
		(fp_line
			(start 0.7874 -0.4064)
			(end 0.7874 0.4064)
			(stroke
				(width 0.1524)
				(type default)
			)
			(layer "F.SilkS")
		)
		(fp_line
			(start 0.7874 0.4064)
			(end -0.7874 0.4064)
			(stroke
				(width 0.1524)
				(type default)
			)
			(layer "F.SilkS")
		)
		(fp_line
			(start -0.67945 -0.305054)
			(end -0.12065 -0.305054)
			(stroke
				(width 0.1)
				(type default)
			)
			(layer "F.Fab")
		)
		(fp_line
			(start -0.67945 0.3048)
			(end -0.67945 -0.305054)
			(stroke
				(width 0.1)
				(type default)
			)
			(layer "F.Fab")
		)
		(fp_line
			(start -0.12065 -0.305054)
			(end -0.12065 -0.2794)
			(stroke
				(width 0.1)
				(type default)
			)
			(layer "F.Fab")
		)
		(fp_line
			(start -0.12065 -0.2794)
			(end 0.12065 -0.2794)
			(stroke
				(width 0.1)
				(type default)
			)
			(layer "F.Fab")
		)
		(fp_line
			(start -0.12065 0.2794)
			(end -0.12065 0.3048)
			(stroke
				(width 0.1)
				(type default)
			)
			(layer "F.Fab")
		)
		(fp_line
			(start -0.12065 0.3048)
			(end -0.67945 0.3048)
			(stroke
				(width 0.1)
				(type default)
			)
			(layer "F.Fab")
		)
		(fp_line
			(start 0.120396 0.2794)
			(end -0.12065 0.2794)
			(stroke
				(width 0.1)
				(type default)
			)
			(layer "F.Fab")
		)
		(fp_line
			(start 0.120396 0.3048)
			(end 0.120396 0.2794)
			(stroke
				(width 0.1)
				(type default)
			)
			(layer "F.Fab")
		)
		(fp_line
			(start 0.12065 -0.3048)
			(end 0.67945 -0.3048)
			(stroke
				(width 0.1)
				(type default)
			)
			(layer "F.Fab")
		)
		(fp_line
			(start 0.12065 -0.2794)
			(end 0.12065 -0.3048)
			(stroke
				(width 0.1)
				(type default)
			)
			(layer "F.Fab")
		)
		(fp_line
			(start 0.67945 -0.3048)
			(end 0.67945 0.3048)
			(stroke
				(width 0.1)
				(type default)
			)
			(layer "F.Fab")
		)
		(fp_line
			(start 0.67945 0.3048)
			(end 0.120396 0.3048)
			(stroke
				(width 0.1)
				(type default)
			)
			(layer "F.Fab")
		)
		(pad "1" smd circle
			(at -0.40005 0)
			(size 0 0)
			(layers "F.Cu" "F.Mask" "F.Paste")
			(net "GND")
		)
		(pad "2" smd circle
			(at 0.40005 0)
			(size 0 0)
			(layers "F.Cu" "F.Mask" "F.Paste")
			(net "P3V3_AUX")
		)
	)
	(footprint ""
		(layer "F.Cu")
		(at 398.782032 -37.025072)
		(property "Reference" "R5709"
			(at 0 0 0)
			(layer "F.SilkS")
			(hide yes)
			(effects
				(font
					(size 1.27 1.27)
				)
			)
		)
		(property "Value" ""
			(at 0 0 0)
			(layer "F.Fab")
			(effects
				(font
					(size 1.27 1.27)
				)
			)
		)
		(duplicate_pad_numbers_are_jumpers no)
		(fp_line
			(start -0.7874 -0.4064)
			(end 0.7874 -0.4064)
			(stroke
				(width 0.1524)
				(type default)
			)
			(layer "F.SilkS")
		)
		(fp_line
			(start -0.7874 0.4064)
			(end -0.7874 -0.4064)
			(stroke
				(width 0.1524)
				(type default)
			)
			(layer "F.SilkS")
		)
		(fp_line
			(start 0.7874 -0.4064)
			(end 0.7874 0.4064)
			(stroke
				(width 0.1524)
				(type default)
			)
			(layer "F.SilkS")
		)
		(fp_line
			(start 0.7874 0.4064)
			(end -0.7874 0.4064)
			(stroke
				(width 0.1524)
				(type default)
			)
			(layer "F.SilkS")
		)
		(fp_line
			(start -0.67945 -0.305054)
			(end -0.12065 -0.305054)
			(stroke
				(width 0.1)
				(type default)
			)
			(layer "F.Fab")
		)
		(fp_line
			(start -0.67945 0.3048)
			(end -0.67945 -0.305054)
			(stroke
				(width 0.1)
				(type default)
			)
			(layer "F.Fab")
		)
		(fp_line
			(start -0.12065 -0.305054)
			(end -0.12065 -0.2794)
			(stroke
				(width 0.1)
				(type default)
			)
			(layer "F.Fab")
		)
		(fp_line
			(start -0.12065 -0.2794)
			(end 0.12065 -0.2794)
			(stroke
				(width 0.1)
				(type default)
			)
			(layer "F.Fab")
		)
		(fp_line
			(start -0.12065 0.2794)
			(end -0.12065 0.3048)
			(stroke
				(width 0.1)
				(type default)
			)
			(layer "F.Fab")
		)
		(fp_line
			(start -0.12065 0.3048)
			(end -0.67945 0.3048)
			(stroke
				(width 0.1)
				(type default)
			)
			(layer "F.Fab")
		)
		(fp_line
			(start 0.120396 0.2794)
			(end -0.12065 0.2794)
			(stroke
				(width 0.1)
				(type default)
			)
			(layer "F.Fab")
		)
		(fp_line
			(start 0.120396 0.3048)
			(end 0.120396 0.2794)
			(stroke
				(width 0.1)
				(type default)
			)
			(layer "F.Fab")
		)
		(fp_line
			(start 0.12065 -0.3048)
			(end 0.67945 -0.3048)
			(stroke
				(width 0.1)
				(type default)
			)
			(layer "F.Fab")
		)
		(fp_line
			(start 0.12065 -0.2794)
			(end 0.12065 -0.3048)
			(stroke
				(width 0.1)
				(type default)
			)
			(layer "F.Fab")
		)
		(fp_line
			(start 0.67945 -0.3048)
			(end 0.67945 0.3048)
			(stroke
				(width 0.1)
				(type default)
			)
			(layer "F.Fab")
		)
		(fp_line
			(start 0.67945 0.3048)
			(end 0.120396 0.3048)
			(stroke
				(width 0.1)
				(type default)
			)
			(layer "F.Fab")
		)
		(pad "1" smd circle
			(at -0.40005 0)
			(size 0 0)
			(layers "F.Cu" "F.Mask" "F.Paste")
			(net "RST_SMB_SSD_R_N")
		)
		(pad "2" smd circle
			(at 0.40005 0)
			(size 0 0)
			(layers "F.Cu" "F.Mask" "F.Paste")
			(net "RST_SMB_SSD14_N")
		)
	)
	(footprint ""
		(layer "F.Cu")
		(at 165.269672 -356.244906 90)
		(property "Reference" "C2516"
			(at 0 0 90)
			(layer "F.SilkS")
			(hide yes)
			(effects
				(font
					(size 1.27 1.27)
				)
			)
		)
		(property "Value" ""
			(at 0 0 90)
			(layer "F.Fab")
			(effects
				(font
					(size 1.27 1.27)
				)
			)
		)
		(duplicate_pad_numbers_are_jumpers no)
		(fp_line
			(start 0.299974 -0.150114)
			(end 0.299974 0.150114)
			(stroke
				(width 0.1)
				(type default)
			)
			(layer "F.Fab")
		)
		(fp_line
			(start -0.299974 -0.150114)
			(end 0.299974 -0.150114)
			(stroke
				(width 0.1)
				(type default)
			)
			(layer "F.Fab")
		)
		(fp_line
			(start 0.299974 0.150114)
			(end -0.299974 0.150114)
			(stroke
				(width 0.1)
				(type default)
			)
			(layer "F.Fab")
		)
		(fp_line
			(start -0.299974 0.150114)
			(end -0.299974 -0.150114)
			(stroke
				(width 0.1)
				(type default)
			)
			(layer "F.Fab")
		)
		(pad "1" smd rect
			(at -0.2667 0 90)
			(size 0.3048 0.381)
			(layers "F.Cu" "F.Mask" "F.Paste")
			(net "P5E_PEX1_STN4_TX_DP<77>")
		)
		(pad "2" smd rect
			(at 0.2667 0 90)
			(size 0.3048 0.381)
			(layers "F.Cu" "F.Mask" "F.Paste")
			(net "P5E_PEX1_STN4_TX_C_DP<77>")
		)
	)
	(footprint ""
		(layer "F.Cu")
		(at 125.16739 -263.57072)
		(property "Reference" "PJ5"
			(at 0 0 0)
			(layer "F.SilkS")
			(hide yes)
			(effects
				(font
					(size 1.27 1.27)
				)
			)
		)
		(property "Value" ""
			(at 0 0 0)
			(layer "F.Fab")
			(effects
				(font
					(size 1.27 1.27)
				)
			)
		)
		(duplicate_pad_numbers_are_jumpers no)
		(pad "1" smd circle
			(at -0.7493 0 90)
			(size 0 0)
			(layers "F.Cu" "F.Mask" "F.Paste")
			(net "SH_P0V8_PEX0_VSEN0_L")
		)
		(pad "2" smd rect
			(at 0.7493 0 270)
			(size 0.7112 0.8128)
			(layers "F.Cu" "F.Mask" "F.Paste")
			(net "SH_P0V8_PEX0_VSEN0_R")
		)
		(zone
			(layer "F.Cu")
			(hatch none 0.5)
			(connect_pads
				(clearance 0)
			)
			(min_thickness 0.25)
			(keepout
				(tracks allowed)
				(vias not_allowed)
				(pads allowed)
				(copperpour not_allowed)
				(footprints allowed)
			)
			(placement
				(enabled no)
				(sheetname "")
			)
			(fill
				(thermal_gap 0.5)
				(thermal_bridge_width 0.5)
				(island_removal_mode 0)
			)
			(polygon
				(pts
					(xy 123.98629 -263.159494) (xy 126.37389 -263.159494) (xy 126.37389 -263.97712) (xy 123.98629 -263.97712)
				)
			)
		)
	)
)
